(kicad_pcb
	(version 20260206)
	(generator "pcbnew")
	(generator_version "10.0")
	(general
		(thickness 1.6)
		(legacy_teardrops no)
	)
	(paper "A4")
	(title_block
		(title "03242023_DA0F0TMBIJ0_F0T_Motherboard_J_brd_V01_OCP.brd")
		(comment 1 "Grand Teton / footprints 1061-1064 of 6105")
	)
	(layers
		(0 "F.Cu" signal "TOP")
		(4 "In1.Cu" signal "GND")
		(6 "In2.Cu" signal "IN1")
		(8 "In3.Cu" signal "GND1")
		(10 "In4.Cu" signal "IN2")
		(12 "In5.Cu" signal "GND2")
		(14 "In6.Cu" signal "IN3")
		(16 "In7.Cu" signal "GND3")
		(18 "In8.Cu" signal "VCC")
		(20 "In9.Cu" signal "VCC1")
		(22 "In10.Cu" signal "GND4")
		(24 "In11.Cu" signal "IN4")
		(26 "In12.Cu" signal "GND5")
		(28 "In13.Cu" signal "IN5")
		(30 "In14.Cu" signal "GND6")
		(32 "In15.Cu" signal "IN6")
		(34 "In16.Cu" signal "GND7")
		(2 "B.Cu" signal "BOTTOM")
		(9 "F.Adhes" user "F.Adhesive")
		(11 "B.Adhes" user "B.Adhesive")
		(13 "F.Paste" user "Package Geometry/Pastemask Top")
		(15 "B.Paste" user "Package Geometry/Pastemask Bottom")
		(5 "F.SilkS" user "Ref Des/Silkscreen Top")
		(7 "B.SilkS" user "Ref Des/Silkscreen Bottom")
		(1 "F.Mask" user "Board Geometry/Soldermask Top")
		(3 "B.Mask" user "Board Geometry/Soldermask Bottom")
		(17 "Dwgs.User" user "User.Drawings")
		(19 "Cmts.User" user "User.Comments")
		(21 "Eco1.User" user "User.Eco1")
		(23 "Eco2.User" user "User.Eco2")
		(25 "Edge.Cuts" user "Board Geometry/Outline")
		(27 "Margin" user)
		(31 "F.CrtYd" user "Package Geometry/Place Bound Top")
		(29 "B.CrtYd" user "Package Geometry/Place Bound Bottom")
		(35 "F.Fab" user "Ref Des/Assembly Top")
		(33 "B.Fab" user "Ref Des/Assembly Bottom")
	)
	(footprint ""
		(layer "F.Cu")
		(at 30.094428 -102.761034 180)
		(property "Reference" "C1347"
			(at 0 0 180)
			(layer "F.SilkS")
			(hide yes)
			(effects
				(font
					(size 1.27 1.27)
				)
			)
		)
		(property "Value" ""
			(at 0 0 180)
			(layer "F.Fab")
			(effects
				(font
					(size 1.27 1.27)
				)
			)
		)
		(duplicate_pad_numbers_are_jumpers no)
		(fp_line
			(start 0.7874 0.4064)
			(end -0.7874 0.4064)
			(stroke
				(width 0.1524)
				(type default)
			)
			(layer "F.SilkS")
		)
		(fp_line
			(start 0.7874 -0.4064)
			(end 0.7874 0.4064)
			(stroke
				(width 0.1524)
				(type default)
			)
			(layer "F.SilkS")
		)
		(fp_line
			(start -0.7874 0.4064)
			(end -0.7874 -0.4064)
			(stroke
				(width 0.1524)
				(type default)
			)
			(layer "F.SilkS")
		)
		(fp_line
			(start -0.7874 -0.4064)
			(end 0.7874 -0.4064)
			(stroke
				(width 0.1524)
				(type default)
			)
			(layer "F.SilkS")
		)
		(fp_line
			(start 0.67945 0.3048)
			(end 0.120396 0.3048)
			(stroke
				(width 0.1)
				(type default)
			)
			(layer "F.Fab")
		)
		(fp_line
			(start 0.67945 -0.3048)
			(end 0.67945 0.3048)
			(stroke
				(width 0.1)
				(type default)
			)
			(layer "F.Fab")
		)
		(fp_line
			(start 0.12065 -0.2794)
			(end 0.12065 -0.3048)
			(stroke
				(width 0.1)
				(type default)
			)
			(layer "F.Fab")
		)
		(fp_line
			(start 0.12065 -0.3048)
			(end 0.67945 -0.3048)
			(stroke
				(width 0.1)
				(type default)
			)
			(layer "F.Fab")
		)
		(fp_line
			(start 0.120396 0.3048)
			(end 0.120396 0.2794)
			(stroke
				(width 0.1)
				(type default)
			)
			(layer "F.Fab")
		)
		(fp_line
			(start 0.120396 0.2794)
			(end -0.12065 0.2794)
			(stroke
				(width 0.1)
				(type default)
			)
			(layer "F.Fab")
		)
		(fp_line
			(start -0.12065 0.3048)
			(end -0.67945 0.3048)
			(stroke
				(width 0.1)
				(type default)
			)
			(layer "F.Fab")
		)
		(fp_line
			(start -0.12065 0.2794)
			(end -0.12065 0.3048)
			(stroke
				(width 0.1)
				(type default)
			)
			(layer "F.Fab")
		)
		(fp_line
			(start -0.12065 -0.2794)
			(end 0.12065 -0.2794)
			(stroke
				(width 0.1)
				(type default)
			)
			(layer "F.Fab")
		)
		(fp_line
			(start -0.12065 -0.305054)
			(end -0.12065 -0.2794)
			(stroke
				(width 0.1)
				(type default)
			)
			(layer "F.Fab")
		)
		(fp_line
			(start -0.67945 0.3048)
			(end -0.67945 -0.305054)
			(stroke
				(width 0.1)
				(type default)
			)
			(layer "F.Fab")
		)
		(fp_line
			(start -0.67945 -0.305054)
			(end -0.12065 -0.305054)
			(stroke
				(width 0.1)
				(type default)
			)
			(layer "F.Fab")
		)
		(pad "1" smd circle
			(at -0.40005 0 180)
			(size 0 0)
			(layers "F.Cu" "F.Mask" "F.Paste")
			(net "MAX11617_VREF")
		)
		(pad "2" smd circle
			(at 0.40005 0 180)
			(size 0 0)
			(layers "F.Cu" "F.Mask" "F.Paste")
			(net "GND")
		)
	)
	(footprint ""
		(layer "F.Cu")
		(at 11.421618 -106.28249 -90)
		(property "Reference" "R2788"
			(at 0 0 270)
			(layer "F.SilkS")
			(hide yes)
			(effects
				(font
					(size 1.27 1.27)
				)
			)
		)
		(property "Value" ""
			(at 0 0 270)
			(layer "F.Fab")
			(effects
				(font
					(size 1.27 1.27)
				)
			)
		)
		(duplicate_pad_numbers_are_jumpers no)
		(fp_line
			(start 0.7874 0.4064)
			(end -0.7874 0.4064)
			(stroke
				(width 0.1524)
				(type default)
			)
			(layer "F.SilkS")
		)
		(fp_line
			(start -0.7874 -0.4064)
			(end 0.00889 -0.4064)
			(stroke
				(width 0.1524)
				(type default)
			)
			(layer "F.SilkS")
		)
		(fp_line
			(start 0.7874 -0.4064)
			(end 0.7874 0.4064)
			(stroke
				(width 0.1524)
				(type default)
			)
			(layer "F.SilkS")
		)
		(fp_line
			(start -0.67945 0.3048)
			(end -0.67945 -0.305054)
			(stroke
				(width 0.1)
				(type default)
			)
			(layer "F.Fab")
		)
		(fp_line
			(start -0.12065 0.3048)
			(end -0.67945 0.3048)
			(stroke
				(width 0.1)
				(type default)
			)
			(layer "F.Fab")
		)
		(fp_line
			(start 0.120396 0.3048)
			(end 0.120396 0.2794)
			(stroke
				(width 0.1)
				(type default)
			)
			(layer "F.Fab")
		)
		(fp_line
			(start 0.67945 0.3048)
			(end 0.120396 0.3048)
			(stroke
				(width 0.1)
				(type default)
			)
			(layer "F.Fab")
		)
		(fp_line
			(start -0.12065 0.2794)
			(end -0.12065 0.3048)
			(stroke
				(width 0.1)
				(type default)
			)
			(layer "F.Fab")
		)
		(fp_line
			(start 0.120396 0.2794)
			(end -0.12065 0.2794)
			(stroke
				(width 0.1)
				(type default)
			)
			(layer "F.Fab")
		)
		(fp_line
			(start -0.12065 -0.2794)
			(end 0.12065 -0.2794)
			(stroke
				(width 0.1)
				(type default)
			)
			(layer "F.Fab")
		)
		(fp_line
			(start 0.12065 -0.2794)
			(end 0.12065 -0.3048)
			(stroke
				(width 0.1)
				(type default)
			)
			(layer "F.Fab")
		)
		(fp_line
			(start 0.12065 -0.3048)
			(end 0.67945 -0.3048)
			(stroke
				(width 0.1)
				(type default)
			)
			(layer "F.Fab")
		)
		(fp_line
			(start 0.67945 -0.3048)
			(end 0.67945 0.3048)
			(stroke
				(width 0.1)
				(type default)
			)
			(layer "F.Fab")
		)
		(fp_line
			(start -0.67945 -0.305054)
			(end -0.12065 -0.305054)
			(stroke
				(width 0.1)
				(type default)
			)
			(layer "F.Fab")
		)
		(fp_line
			(start -0.12065 -0.305054)
			(end -0.12065 -0.2794)
			(stroke
				(width 0.1)
				(type default)
			)
			(layer "F.Fab")
		)
		(pad "1" smd rect
			(at -0.40005 0 90)
			(size 0.4572 0.508)
			(layers "F.Cu" "F.Mask" "F.Paste")
			(net "USB2_HOST_BMC_B_BUF_DP")
		)
		(pad "2" smd rect
			(at 0.40005 0 90)
			(size 0.4572 0.508)
			(layers "F.Cu" "F.Mask" "F.Paste")
			(net "USB2_HUB_BUF_SWB_R_DP")
		)
	)
	(footprint ""
		(layer "F.Cu")
		(at 118.542816 -255.0541 90)
		(property "Reference" "C244"
			(at 0 0 90)
			(layer "F.SilkS")
			(hide yes)
			(effects
				(font
					(size 1.27 1.27)
				)
			)
		)
		(property "Value" ""
			(at 0 0 90)
			(layer "F.Fab")
			(effects
				(font
					(size 1.27 1.27)
				)
			)
		)
		(duplicate_pad_numbers_are_jumpers no)
		(fp_line
			(start 0.7874 -0.4064)
			(end 0.7874 0.4064)
			(stroke
				(width 0.1524)
				(type default)
			)
			(layer "F.SilkS")
		)
		(fp_line
			(start -0.7874 -0.4064)
			(end 0.7874 -0.4064)
			(stroke
				(width 0.1524)
				(type default)
			)
			(layer "F.SilkS")
		)
		(fp_line
			(start 0.7874 0.4064)
			(end -0.7874 0.4064)
			(stroke
				(width 0.1524)
				(type default)
			)
			(layer "F.SilkS")
		)
		(fp_line
			(start -0.7874 0.4064)
			(end -0.7874 -0.4064)
			(stroke
				(width 0.1524)
				(type default)
			)
			(layer "F.SilkS")
		)
		(fp_line
			(start -0.12065 -0.305054)
			(end -0.12065 -0.2794)
			(stroke
				(width 0.1)
				(type default)
			)
			(layer "F.Fab")
		)
		(fp_line
			(start -0.67945 -0.305054)
			(end -0.12065 -0.305054)
			(stroke
				(width 0.1)
				(type default)
			)
			(layer "F.Fab")
		)
		(fp_line
			(start 0.67945 -0.3048)
			(end 0.67945 0.3048)
			(stroke
				(width 0.1)
				(type default)
			)
			(layer "F.Fab")
		)
		(fp_line
			(start 0.12065 -0.3048)
			(end 0.67945 -0.3048)
			(stroke
				(width 0.1)
				(type default)
			)
			(layer "F.Fab")
		)
		(fp_line
			(start 0.12065 -0.2794)
			(end 0.12065 -0.3048)
			(stroke
				(width 0.1)
				(type default)
			)
			(layer "F.Fab")
		)
		(fp_line
			(start -0.12065 -0.2794)
			(end 0.12065 -0.2794)
			(stroke
				(width 0.1)
				(type default)
			)
			(layer "F.Fab")
		)
		(fp_line
			(start 0.120396 0.2794)
			(end -0.12065 0.2794)
			(stroke
				(width 0.1)
				(type default)
			)
			(layer "F.Fab")
		)
		(fp_line
			(start -0.12065 0.2794)
			(end -0.12065 0.3048)
			(stroke
				(width 0.1)
				(type default)
			)
			(layer "F.Fab")
		)
		(fp_line
			(start 0.67945 0.3048)
			(end 0.120396 0.3048)
			(stroke
				(width 0.1)
				(type default)
			)
			(layer "F.Fab")
		)
		(fp_line
			(start 0.120396 0.3048)
			(end 0.120396 0.2794)
			(stroke
				(width 0.1)
				(type default)
			)
			(layer "F.Fab")
		)
		(fp_line
			(start -0.12065 0.3048)
			(end -0.67945 0.3048)
			(stroke
				(width 0.1)
				(type default)
			)
			(layer "F.Fab")
		)
		(fp_line
			(start -0.67945 0.3048)
			(end -0.67945 -0.305054)
			(stroke
				(width 0.1)
				(type default)
			)
			(layer "F.Fab")
		)
		(pad "1" smd circle
			(at -0.40005 0 90)
			(size 0 0)
			(layers "F.Cu" "F.Mask" "F.Paste")
			(net "PVCCIN_CPU1")
		)
		(pad "2" smd circle
			(at 0.40005 0 90)
			(size 0 0)
			(layers "F.Cu" "F.Mask" "F.Paste")
			(net "GND")
		)
	)
	(footprint ""
		(layer "F.Cu")
		(at 302.768 -46.319948)
		(property "Reference" "C1248"
			(at 0 0 0)
			(layer "F.SilkS")
			(hide yes)
			(effects
				(font
					(size 1.27 1.27)
				)
			)
		)
		(property "Value" ""
			(at 0 0 0)
			(layer "F.Fab")
			(effects
				(font
					(size 1.27 1.27)
				)
			)
		)
		(duplicate_pad_numbers_are_jumpers no)
		(fp_line
			(start -1.524 -0.762)
			(end 1.524 -0.762)
			(stroke
				(width 0.1524)
				(type default)
			)
			(layer "F.SilkS")
		)
		(fp_line
			(start -1.524 0.762)
			(end -1.524 -0.762)
			(stroke
				(width 0.1524)
				(type default)
			)
			(layer "F.SilkS")
		)
		(fp_line
			(start 1.524 -0.762)
			(end 1.524 0.762)
			(stroke
				(width 0.1524)
				(type default)
			)
			(layer "F.SilkS")
		)
		(fp_line
			(start 1.524 0.762)
			(end -1.524 0.762)
			(stroke
				(width 0.1524)
				(type default)
			)
			(layer "F.SilkS")
		)
		(fp_line
			(start -1.1049 -0.724916)
			(end -1.1049 0.724916)
			(stroke
				(width 0.1)
				(type default)
			)
			(layer "F.Fab")
		)
		(fp_line
			(start -1.1049 0.724916)
			(end 1.1049 0.724916)
			(stroke
				(width 0.1)
				(type default)
			)
			(layer "F.Fab")
		)
		(fp_line
			(start 1.1049 -0.724916)
			(end -1.1049 -0.724916)
			(stroke
				(width 0.1)
				(type default)
			)
			(layer "F.Fab")
		)
		(fp_line
			(start 1.1049 0.724916)
			(end 1.1049 -0.724916)
			(stroke
				(width 0.1)
				(type default)
			)
			(layer "F.Fab")
		)
		(pad "1" smd rect
			(at -0.889 0 180)
			(size 1.016 1.27)
			(layers "F.Cu" "F.Mask" "F.Paste")
			(net "P1V05_PCH_AUX")
		)
		(pad "2" smd rect
			(at 0.889 0 180)
			(size 1.016 1.27)
			(layers "F.Cu" "F.Mask" "F.Paste")
			(net "GND")
		)
	)
)
